FILE_TYPE = CONNECTIVITY;
{Allegro Design Entry HDL 17.2-2016 S081 (4005846) 1/11/2022}
"PAGE_NUMBER" = 17;
0"NC";
1"P5V_AUX\g";
2"P3V3_AUX\g";
3"P1V2_AUX\g";
4"P1V8_AUX\g";
5"P2V5_AUX\g";
6"P3V3_AUX\g";
7"P1V0_AUX\g";
8"P1V0_AUX\g";
9"P1V8_AUX\g";
10"P1V0_AUX\g";
11"P1V2_AUX\g";
12"P1V0_AUX\g";
13"P1V0_AUX\g";
14"P1V2_AUX\g";
15"P1V2_AUX\g";
16"P2V5_AUX\g";
17"P1V8_AUX\g";
18"P1V8_AUX\g";
19"P3V3_AUX\g";
20"P3V3_AUX\g";
21"P1V8_AUX\g";
22"P1V2_P1V0_I3C_VDDL1\g";
23"P1V2_AUX\g";
24"P1V2_P1V0_I3C_VDDL2\g";
25"PGPPA_BMC_AUX\g";
26"P1V8_AUX\g";
27"P3V3_P1V8_I2C_I3C\g";
28"P1V8_AUX\g";
29"GND\g";
30"GND\g";
31"GND\g";
32"GND\g";
33"GND\g";
34"GND\g";
35"GND\g";
36"GND\g";
37"GND\g";
38"GND\g";
39"GND\g";
40"GND\g";
41"GND\g";
42"GND\g";
43"GND\g";
44"GND\g";
45"GND\g";
46"GND\g";
47"GND\g";
48"GND\g";
49"GND\g";
50"GND\g";
51"GND\g";
52"LPC_ESPI_SEL_N";
53"LPC_ESPI_SEL_R";
54"LPC_ESPI_SEL";
55"PGPPA_BMC_AUX_L";
56"P1V0_STBY_RC_VCC10A";
57"A_BMC_ADCVREFN1";
58"A_BMC_ADCVREFP1";
59"P1V0_STBY_DP_VCC10A";
60"P1V8_STBY_DP_VCC18A";
61"P3V3_STBY_PLLAHVDD";
62"P3V3_STBY_DACAV33";
63"ADCVREFEXT0";
64"A_BMC_ADCVREFP0";
65"A_BMC_ADCVREFN0";
66"P1V8_STBY_AVDDPLL";
67"ADCVREFEXT1";
68"P1V0_STBY_PE_VCC10A";
69"P1V8_STBY_RC_VCC18A";
%"UNIVERSAL_GND"
"1","(-3900,-650)","0","logical_power","I1";
;
CDS_LIB"logical_power"
HDL_POWER"GND";
"A"50;
%"UNIVERSAL_POWER"
"1","(4550,3400)","0","logical_power","I100";
;
HDL_POWER"P1V2_P1V0_I3C_VDDL2"
CDS_LIB"logical_power";
"A"24;
%"Q_RES"
"1","(3350,3925)","0","pure_quanta","I101";
;
VALUE"0"
TOLERANCE"5%"
MATERIAL"EMPTY"
WATTAGE"1/16W"
PACK_TYPE"0402LF"
PART_NUMBER"CS00002JB13"
CDS_LIB"pure_quanta"
LOCATION"R278"
$SEC"1"
CDS_SEC"1";
"B"
$PN"2"22;
"A"
$PN"1"23;
%"UNIVERSAL_POWER"
"1","(2925,4175)","0","logical_power","I102";
;
HDL_POWER"P1V2_AUX"
CDS_LIB"logical_power";
"A"23;
%"UNIVERSAL_GND"
"1","(75,3175)","0","logical_power","I103";
;
CDS_LIB"logical_power"
HDL_POWER"GND";
"A"49;
%"Q_CAP"
"2","(350,3300)","0","pure_quanta","I104";
;
VALUE"0.01UF"
CDS_LIB"pure_quanta"
PART_NUMBER"CH31006KB18"
VOLTAGE"50V"
MATERIAL"X7R"
TOLERANCE"10%"
PACK_TYPE"C0402"
LOCATION"C133"
$SEC"1"
CDS_SEC"1";
"A"
$PN"1"49;
"B"
$PN"2"57;
%"UNIVERSAL_GND"
"1","(125,3775)","0","logical_power","I105";
;
CDS_LIB"logical_power"
HDL_POWER"GND";
"A"48;
%"Q_CAP"
"2","(400,3900)","0","pure_quanta","I106";
;
VALUE"0.01UF"
CDS_LIB"pure_quanta"
PART_NUMBER"CH31006KB18"
VOLTAGE"50V"
MATERIAL"X7R"
TOLERANCE"10%"
PACK_TYPE"C0402"
LOCATION"C134"
$SEC"1"
CDS_SEC"1";
"A"
$PN"1"48;
"B"
$PN"2"65;
%"Q_CAP"
"2","(775,3425)","0","pure_quanta","I107";
;
PART_NUMBER"CH31006KB18"
VALUE"0.01UF"
VOLTAGE"50V"
TOLERANCE"10%"
PACK_TYPE"C0402"
MATERIAL"X7R"
CDS_LIB"pure_quanta"
LOCATION"C135"
$SEC"1"
CDS_SEC"1";
"A"
$PN"1"49;
"B"
$PN"2"58;
%"Q_CAP"
"2","(1000,3300)","0","pure_quanta","I108";
;
VALUE"0.01UF"
CDS_LIB"pure_quanta"
PART_NUMBER"CH31006KB18"
VOLTAGE"50V"
MATERIAL"X7R"
TOLERANCE"10%"
PACK_TYPE"C0402"
LOCATION"C137"
$SEC"1"
CDS_SEC"1";
"A"
$PN"1"57;
"B"
$PN"2"58;
%"Q_CAP"
"2","(1050,3900)","0","pure_quanta","I109";
;
VALUE"0.01UF"
CDS_LIB"pure_quanta"
PART_NUMBER"CH31006KB18"
VOLTAGE"50V"
MATERIAL"X7R"
TOLERANCE"10%"
PACK_TYPE"C0402"
LOCATION"C138"
$SEC"1"
CDS_SEC"1";
"A"
$PN"1"65;
"B"
$PN"2"64;
%"Q_CAP"
"2","(825,4025)","0","pure_quanta","I110";
;
PART_NUMBER"CH31006KB18"
VOLTAGE"50V"
MATERIAL"X7R"
TOLERANCE"10%"
PACK_TYPE"C0402"
VALUE"0.01UF"
CDS_LIB"pure_quanta"
LOCATION"C136"
$SEC"1"
CDS_SEC"1";
"A"
$PN"1"48;
"B"
$PN"2"64;
%"UNIVERSAL_POWER"
"1","(4550,4150)","0","logical_power","I111";
;
HDL_POWER"P1V2_P1V0_I3C_VDDL1"
CDS_LIB"logical_power";
"A"22;
%"Q_CAP"
"1","(-925,3875)","0","pure_quanta","I118";
;
PART_NUMBER"CH4104K1B00"
VOLTAGE"25V"
MATERIAL"X7R"
TOLERANCE"10%"
VALUE"0.1UF"
PACK_TYPE"0402"
CDS_LIB"pure_quanta"
LOCATION"C49"
$SEC"1"
CDS_SEC"1";
"B"
$PN"2"47;
"A"
$PN"1"66;
%"Q_INDUCTOR"
"1","(-1425,4075)","0","pure_quanta","I120";
;
PART_NUMBER"CX8PG121009"
MATERIAL"IND"
VALUE"BLM18PG121SN1D/2000MA"
PACK_TYPE"SMLF"
CDS_LIB"pure_quanta"
NEEDS_NO_SIZE"TRUE"
LOCATION"L5"
$SEC"1"
CDS_SEC"1";
"1"
$PN"1"21;
"2"
$PN"2"66;
%"UNIVERSAL_POWER"
"1","(-1725,4125)","0","logical_power","I121";
;
HDL_POWER"P1V8_AUX"
CDS_LIB"logical_power";
"A"21;
%"Q_CAP"
"1","(-1125,3875)","0","pure_quanta","I122";
;
PART_NUMBER"CH5104KEB02"
VOLTAGE"25V"
TOLERANCE"10%"
MATERIAL"X6S"
PACK_TYPE"C0402"
VALUE"1UF"
CDS_LIB"pure_quanta"
LOCATION"C46"
$SEC"1"
CDS_SEC"1";
"B"
$PN"2"47;
"A"
$PN"1"66;
%"UNIVERSAL_GND"
"1","(-1025,3600)","0","logical_power","I123";
;
CDS_LIB"logical_power"
HDL_POWER"GND";
"A"47;
%"Q_INDUCTOR"
"1","(-1400,3200)","0","pure_quanta","I124";
;
VALUE"BLM18PG121SN1D/2000MA"
PACK_TYPE"SMLF"
MATERIAL"IND"
PART_NUMBER"CX8PG121009"
CDS_LIB"pure_quanta"
NEEDS_NO_SIZE"TRUE"
LOCATION"L6"
$SEC"1"
CDS_SEC"1";
"1"
$PN"1"7;
"2"
$PN"2"56;
%"UNIVERSAL_POWER"
"1","(-1700,3250)","0","logical_power","I125";
;
HDL_POWER"P1V0_AUX"
CDS_LIB"logical_power";
"A"7;
%"Q_CAP"
"1","(-900,3000)","0","pure_quanta","I126";
;
VALUE"0.1UF"
VOLTAGE"25V"
PART_NUMBER"CH4104K1B00"
MATERIAL"X7R"
TOLERANCE"10%"
PACK_TYPE"0402"
CDS_LIB"pure_quanta"
LOCATION"C50"
$SEC"1"
CDS_SEC"1";
"B"
$PN"2"46;
"A"
$PN"1"56;
%"UNIVERSAL_GND"
"1","(-1000,2725)","0","logical_power","I127";
;
CDS_LIB"logical_power"
HDL_POWER"GND";
"A"46;
%"Q_CAP"
"1","(-1100,3000)","0","pure_quanta","I128";
;
PACK_TYPE"C0402"
VOLTAGE"25V"
VALUE"1UF"
PART_NUMBER"CH5104KEB02"
MATERIAL"X6S"
TOLERANCE"10%"
CDS_LIB"pure_quanta"
LOCATION"C47"
$SEC"1"
CDS_SEC"1";
"B"
$PN"2"46;
"A"
$PN"1"56;
%"UNIVERSAL_POWER"
"1","(225,2300)","0","logical_power","I130";
;
HDL_POWER"P3V3_P1V8_I2C_I3C"
CDS_LIB"logical_power";
"A"27;
%"Q_RES"
"1","(-975,2050)","0","pure_quanta","I131";
;
TOLERANCE"5%"
PACK_TYPE"0402LF"
WATTAGE"1/16W"
VALUE"0"
PART_NUMBER"CS00002JB13"
MATERIAL"CHIP"
CDS_LIB"pure_quanta"
LOCATION"R231"
$SEC"1"
CDS_SEC"1";
"B"
$PN"2"27;
"A"
$PN"1"6;
%"UNIVERSAL_POWER"
"1","(-1350,2300)","0","logical_power","I132";
;
HDL_POWER"P3V3_AUX"
CDS_LIB"logical_power";
"A"6;
%"Q_CAP"
"1","(100,1875)","0","pure_quanta","I133";
;
VOLTAGE"25V"
MATERIAL"X7R"
TOLERANCE"10%"
VALUE"0.1UF"
PART_NUMBER"CH4104K1B00"
PACK_TYPE"0402"
CDS_LIB"pure_quanta"
LOCATION"C57"
$SEC"1"
CDS_SEC"1";
"B"
$PN"2"45;
"A"
$PN"1"27;
%"UNIVERSAL_GND"
"1","(-75,1575)","0","logical_power","I134";
;
CDS_LIB"logical_power"
HDL_POWER"GND";
"A"45;
%"Q_CAP"
"1","(-250,1875)","0","pure_quanta","I135";
;
MATERIAL"X6S"
PART_NUMBER"CH5104KEB02"
VOLTAGE"25V"
VALUE"1UF"
TOLERANCE"10%"
PACK_TYPE"C0402"
CDS_LIB"pure_quanta"
LOCATION"C53"
$SEC"1"
CDS_SEC"1";
"B"
$PN"2"45;
"A"
$PN"1"27;
%"Q_RES"
"1","(-875,1775)","0","pure_quanta","I136";
;
VALUE"0"
MATERIAL"EMPTY"
PACK_TYPE"0402LF"
PART_NUMBER"CS00002JB13"
TOLERANCE"5%"
WATTAGE"1/16W"
CDS_LIB"pure_quanta"
LOCATION"R232"
$SEC"1"
CDS_SEC"1";
"B"
$PN"2"27;
"A"
$PN"1"26;
%"UNIVERSAL_POWER"
"1","(-1450,1925)","0","logical_power","I137";
;
HDL_POWER"P1V8_AUX"
CDS_LIB"logical_power";
"A"26;
%"Q_CAP"
"1","(425,875)","0","pure_quanta","I139";
;
PART_NUMBER"CH4104K1B00"
VOLTAGE"25V"
MATERIAL"X7R"
TOLERANCE"10%"
VALUE"0.1UF"
PACK_TYPE"0402"
CDS_LIB"pure_quanta"
LOCATION"C65"
$SEC"1"
CDS_SEC"1";
"B"
$PN"2"44;
"A"
$PN"1"61;
%"UNIVERSAL_GND"
"1","(300,600)","0","logical_power","I140";
;
CDS_LIB"logical_power"
HDL_POWER"GND";
"A"44;
%"Q_CAP"
"1","(225,875)","0","pure_quanta","I141";
;
MATERIAL"X6S"
TOLERANCE"10%"
PACK_TYPE"C0402"
VOLTAGE"25V"
VALUE"1UF"
PART_NUMBER"CH5104KEB02"
CDS_LIB"pure_quanta"
LOCATION"C60"
$SEC"1"
CDS_SEC"1";
"B"
$PN"2"44;
"A"
$PN"1"61;
%"Q_INDUCTOR"
"1","(-125,1075)","0","pure_quanta","I142";
;
PACK_TYPE"SMLF"
VALUE"BLM18PG121SN1D/2000MA"
MATERIAL"EMPTY"
PART_NUMBER"CX8PG121009"
NEEDS_NO_SIZE"TRUE"
CDS_LIB"pure_quanta"
LOCATION"L9"
$SEC"1"
CDS_SEC"1";
"1"
$PN"1"20;
"2"
$PN"2"61;
%"UNIVERSAL_POWER"
"1","(-475,1250)","0","logical_power","I143";
;
HDL_POWER"P3V3_AUX"
CDS_LIB"logical_power";
"A"20;
%"Q_CAP"
"1","(-900,750)","0","pure_quanta","I145";
;
VOLTAGE"25V"
TOLERANCE"10%"
PACK_TYPE"0402"
MATERIAL"X7R"
PART_NUMBER"CH4104K1B00"
VALUE"0.1UF"
CDS_LIB"pure_quanta"
LOCATION"C51"
$SEC"1"
CDS_SEC"1";
"B"
$PN"2"43;
"A"
$PN"1"62;
%"Q_INDUCTOR"
"1","(-1400,950)","0","pure_quanta","I146";
;
PACK_TYPE"SMLF"
PART_NUMBER"CX8PG121009"
MATERIAL"IND"
VALUE"BLM18PG121SN1D/2000MA"
CDS_LIB"pure_quanta"
NEEDS_NO_SIZE"TRUE"
LOCATION"L7"
$SEC"1"
CDS_SEC"1";
"1"
$PN"1"19;
"2"
$PN"2"62;
%"UNIVERSAL_POWER"
"1","(-1700,1000)","0","logical_power","I147";
;
HDL_POWER"P3V3_AUX"
CDS_LIB"logical_power";
"A"19;
%"Q_CAP"
"1","(-1100,750)","0","pure_quanta","I148";
;
TOLERANCE"10%"
PART_NUMBER"CH5104KEB02"
VALUE"1UF"
PACK_TYPE"C0402"
MATERIAL"X6S"
VOLTAGE"25V"
CDS_LIB"pure_quanta"
LOCATION"C48"
$SEC"1"
CDS_SEC"1";
"B"
$PN"2"43;
"A"
$PN"1"62;
%"UNIVERSAL_GND"
"1","(-1000,475)","0","logical_power","I149";
;
CDS_LIB"logical_power"
HDL_POWER"GND";
"A"43;
%"Q_CAP"
"1","(350,-250)","0","pure_quanta","I151";
;
PART_NUMBER"CH4104K1B00"
VOLTAGE"25V"
MATERIAL"X7R"
TOLERANCE"10%"
VALUE"0.1UF"
PACK_TYPE"0402"
CDS_LIB"pure_quanta"
LOCATION"C81"
$SEC"1"
CDS_SEC"1";
"B"
$PN"2"42;
"A"
$PN"1"69;
%"UNIVERSAL_GND"
"1","(250,-525)","0","logical_power","I152";
;
CDS_LIB"logical_power"
HDL_POWER"GND";
"A"42;
%"Q_CAP"
"1","(150,-250)","0","pure_quanta","I153";
;
PART_NUMBER"CH5104KEB02"
VALUE"1UF"
VOLTAGE"25V"
MATERIAL"X6S"
TOLERANCE"10%"
PACK_TYPE"C0402"
CDS_LIB"pure_quanta"
LOCATION"C80"
$SEC"1"
CDS_SEC"1";
"B"
$PN"2"42;
"A"
$PN"1"69;
%"Q_INDUCTOR"
"1","(-150,-50)","0","pure_quanta","I154";
;
MATERIAL"IND"
PART_NUMBER"CX8PG121009"
PACK_TYPE"SMLF"
VALUE"BLM18PG121SN1D/2000MA"
CDS_LIB"pure_quanta"
NEEDS_NO_SIZE"TRUE"
LOCATION"L14"
$SEC"1"
CDS_SEC"1";
"1"
$PN"1"28;
"2"
$PN"2"69;
%"UNIVERSAL_POWER"
"1","(-450,0)","0","logical_power","I155";
;
HDL_POWER"P1V8_AUX"
CDS_LIB"logical_power";
"A"28;
%"Q_CAP"
"1","(-975,-300)","0","pure_quanta","I157";
;
VALUE"0.1UF"
PART_NUMBER"CH4104K1B00"
VOLTAGE"25V"
MATERIAL"X7R"
TOLERANCE"10%"
PACK_TYPE"0402"
CDS_LIB"pure_quanta"
LOCATION"C79"
$SEC"1"
CDS_SEC"1";
"B"
$PN"2"41;
"A"
$PN"1"68;
%"Q_INDUCTOR"
"1","(-1475,-100)","0","pure_quanta","I158";
;
PACK_TYPE"SMLF"
MATERIAL"IND"
PART_NUMBER"CX8PG121009"
VALUE"BLM18PG121SN1D/2000MA"
CDS_LIB"pure_quanta"
NEEDS_NO_SIZE"TRUE"
LOCATION"L13"
$SEC"1"
CDS_SEC"1";
"1"
$PN"1"10;
"2"
$PN"2"68;
%"UNIVERSAL_POWER"
"1","(-1775,-50)","0","logical_power","I159";
;
HDL_POWER"P1V0_AUX"
CDS_LIB"logical_power";
"A"10;
%"Q_CAP"
"1","(-1175,-300)","0","pure_quanta","I160";
;
PART_NUMBER"CH5104KEB02"
VOLTAGE"25V"
VALUE"1UF"
MATERIAL"X6S"
TOLERANCE"10%"
PACK_TYPE"C0402"
CDS_LIB"pure_quanta"
LOCATION"C78"
$SEC"1"
CDS_SEC"1";
"B"
$PN"2"41;
"A"
$PN"1"68;
%"UNIVERSAL_GND"
"1","(-1075,-575)","0","logical_power","I161";
;
CDS_LIB"logical_power"
HDL_POWER"GND";
"A"41;
%"Q_CAP"
"1","(3625,2000)","0","pure_quanta","I163";
;
VALUE"0.1UF"
VOLTAGE"25V"
PART_NUMBER"CH4104K1B00"
MATERIAL"X7R"
TOLERANCE"10%"
PACK_TYPE"0402"
CDS_LIB"pure_quanta"
LOCATION"C130"
$SEC"1"
CDS_SEC"1";
"B"
$PN"2"40;
"A"
$PN"1"60;
%"UNIVERSAL_GND"
"1","(3525,1725)","0","logical_power","I164";
;
CDS_LIB"logical_power"
HDL_POWER"GND";
"A"40;
%"Q_CAP"
"1","(3425,2000)","0","pure_quanta","I165";
;
VALUE"1UF"
PART_NUMBER"CH5104KEB02"
VOLTAGE"25V"
MATERIAL"X6S"
TOLERANCE"10%"
PACK_TYPE"C0402"
CDS_LIB"pure_quanta"
LOCATION"C128"
$SEC"1"
CDS_SEC"1";
"B"
$PN"2"40;
"A"
$PN"1"60;
%"Q_INDUCTOR"
"1","(3125,2200)","0","pure_quanta","I166";
;
MATERIAL"IND"
PACK_TYPE"SMLF"
VALUE"BLM18PG121SN1D/2000MA"
PART_NUMBER"CX8PG121009"
NEEDS_NO_SIZE"TRUE"
CDS_LIB"pure_quanta"
LOCATION"L16"
$SEC"1"
CDS_SEC"1";
"1"
$PN"1"18;
"2"
$PN"2"60;
%"UNIVERSAL_POWER"
"1","(2825,2250)","0","logical_power","I167";
;
HDL_POWER"P1V8_AUX"
CDS_LIB"logical_power";
"A"18;
%"Q_CAP"
"1","(2250,1950)","0","pure_quanta","I169";
;
VOLTAGE"25V"
PART_NUMBER"CH4104K1B00"
MATERIAL"X7R"
TOLERANCE"10%"
VALUE"0.1UF"
PACK_TYPE"0402"
CDS_LIB"pure_quanta"
LOCATION"C97"
$SEC"1"
CDS_SEC"1";
"B"
$PN"2"39;
"A"
$PN"1"59;
%"Q_INDUCTOR"
"1","(1750,2150)","0","pure_quanta","I170";
;
PART_NUMBER"CX8PG121009"
VALUE"BLM18PG121SN1D/2000MA"
PACK_TYPE"SMLF"
MATERIAL"IND"
NEEDS_NO_SIZE"TRUE"
CDS_LIB"pure_quanta"
LOCATION"L15"
$SEC"1"
CDS_SEC"1";
"1"
$PN"1"8;
"2"
$PN"2"59;
%"UNIVERSAL_POWER"
"1","(1450,2200)","0","logical_power","I171";
;
HDL_POWER"P1V0_AUX"
CDS_LIB"logical_power";
"A"8;
%"UNIVERSAL_GND"
"1","(2150,1675)","0","logical_power","I172";
;
CDS_LIB"logical_power"
HDL_POWER"GND";
"A"39;
%"Q_CAP"
"1","(2050,1950)","0","pure_quanta","I173";
;
VOLTAGE"25V"
VALUE"1UF"
PART_NUMBER"CH5104KEB02"
MATERIAL"X6S"
TOLERANCE"10%"
PACK_TYPE"C0402"
CDS_LIB"pure_quanta"
LOCATION"C90"
$SEC"1"
CDS_SEC"1";
"B"
$PN"2"39;
"A"
$PN"1"59;
%"UNIVERSAL_POWER"
"1","(1600,550)","0","logical_power","I174";
;
HDL_POWER"PGPPA_BMC_AUX"
CDS_LIB"logical_power";
"A"25;
%"Q_INDUCTOR"
"1","(2325,450)","2","pure_quanta","I176";
;
MATERIAL"IND"
PACK_TYPE"SMLF"
PART_NUMBER"CX8EG121000"
VALUE"BLM18EG121SN1D/2A"
NEEDS_NO_SIZE"TRUE"
CDS_LIB"pure_quanta"
LOCATION"L17"
$SEC"1"
CDS_SEC"1";
"1"
$PN"1"55;
"2"
$PN"2"25;
%"Q_CAP"
"1","(2050,250)","0","pure_quanta","I178";
;
PART_NUMBER"CH4104K1B00"
MATERIAL"X7R"
TOLERANCE"10%"
PACK_TYPE"0402"
VOLTAGE"25V"
VALUE"0.1UF"
CDS_LIB"pure_quanta"
LOCATION"C96"
$SEC"1"
CDS_SEC"1";
"B"
$PN"2"30;
"A"
$PN"1"25;
%"UNIVERSAL_GND"
"1","(2050,0)","0","logical_power","I179";
;
CDS_LIB"logical_power"
HDL_POWER"GND";
"A"30;
%"Q_CAP"
"1","(1650,250)","0","pure_quanta","I180";
;
PART_NUMBER"CH6101MEB01"
VOLTAGE"6.3V"
MATERIAL"X6S"
TOLERANCE"20%"
VALUE"10UF"
PACK_TYPE"C0402"
CDS_LIB"pure_quanta"
LOCATION"C224"
$SEC"1"
CDS_SEC"1";
"B"
$PN"2"51;
"A"
$PN"1"25;
%"UNIVERSAL_GND"
"1","(1650,50)","0","logical_power","I181";
;
CDS_LIB"logical_power"
HDL_POWER"GND";
"A"51;
%"UNIVERSAL_GND"
"1","(-2300,-625)","0","logical_power","I2";
;
CDS_LIB"logical_power"
HDL_POWER"GND";
"A"38;
%"MOSFET_N_GSD"
"1","(2850,-1125)","2","pure_quanta","I227";
;
PART_NUMBER"BAM69680000"
PART_TYPE"SMLF"
MATERIAL"IC"
VALUE"DMG6968U-7"
SEC_TYPE""
CDS_LIB"pure_quanta"
NEEDS_NO_SIZE"TRUE"
CDS_LMAN_SYM_OUTLINE"-100,100,100,-100"
LOCATION"Q10"
SEC"1";
"DRAIN"
$PN"D"52;
"SOURCE"
$PN"S"37;
"GATE"
$PN"G"53;
%"Q_RES"
"1","(3775,-1175)","0","pure_quanta","I228";
;
MATERIAL"CHIP"
VALUE"33.2"
CDS_LIB"pure_quanta"
WATTAGE"1/16W"
PACK_TYPE"0402LF"
PART_NUMBER"CS03322FB03"
TOLERANCE"1%"
LOCATION"R713"
$SEC"1"
CDS_SEC"1";
"B"
$PN"2"54;
"A"
$PN"1"53;
%"Q_RES"
"2","(2825,-600)","0","pure_quanta","I230";
;
WATTAGE"1/16W"
MATERIAL"CHIP"
VALUE"10K"
TOLERANCE"1%"
PART_NUMBER"CS31002FB08"
PACK_TYPE"0402LF"
CDS_LIB"pure_quanta"
LOCATION"R716"
$SEC"1"
CDS_SEC"1";
"A"
$PN"1"1;
"B"
$PN"2"52;
%"UNIVERSAL_GND"
"1","(2825,-1650)","0","logical_power","I232";
;
CDS_LIB"logical_power"
HDL_POWER"GND";
"A"37;
%"UNIVERSAL_GND"
"1","(3300,-1625)","0","logical_power","I233";
;
CDS_LIB"logical_power"
HDL_POWER"GND";
"A"36;
%"Q_CAP"
"1","(3300,-1400)","0","pure_quanta","I234";
;
PACK_TYPE"0402"
MATERIAL"EMPTY"
TOLERANCE"10%"
VOLTAGE"16V"
PART_NUMBER"TMP_QCH5103K9B00"
VALUE"1UF"
CDS_LIB"pure_quanta"
LOCATION"C273"
$SEC"1"
CDS_SEC"1";
"B"
$PN"2"36;
"A"
$PN"1"53;
%"UNIVERSAL_POWER"
"1","(2825,-350)","0","logical_power","I236";
;
HDL_POWER"P5V_AUX"
CDS_LIB"logical_power";
"A"1;
%"Q_CAP"
"1","(2200,-1375)","0","pure_quanta","I239";
;
PART_NUMBER"TMP_QCH5103K9B00"
VOLTAGE"16V"
VALUE"1UF"
TOLERANCE"10%"
PACK_TYPE"0402"
MATERIAL"EMPTY"
CDS_LIB"pure_quanta"
LOCATION"C270"
$SEC"1"
CDS_SEC"1";
"B"
$PN"2"35;
"A"
$PN"1"52;
%"UNIVERSAL_GND"
"1","(2200,-1600)","0","logical_power","I240";
;
CDS_LIB"logical_power"
HDL_POWER"GND";
"A"35;
%"Q_CAP"
"1","(-250,-1225)","0","pure_quanta","I250";
;
PART_NUMBER"CH4104K1B00"
VOLTAGE"25V"
MATERIAL"X7R"
TOLERANCE"10%"
VALUE"0.1UF"
PACK_TYPE"0402"
CDS_LIB"pure_quanta"
LOCATION"C284"
$SEC"1"
CDS_SEC"1";
"B"
$PN"2"34;
"A"
$PN"1"63;
%"UNIVERSAL_GND"
"1","(-425,-1525)","0","logical_power","I251";
;
CDS_LIB"logical_power"
HDL_POWER"GND";
"A"34;
%"Q_CAP"
"1","(-600,-1225)","0","pure_quanta","I252";
;
VOLTAGE"25V"
VALUE"1UF"
PART_NUMBER"CH5104KEB02"
MATERIAL"X6S"
TOLERANCE"10%"
PACK_TYPE"C0402"
CDS_LIB"pure_quanta"
LOCATION"C282"
$SEC"1"
CDS_SEC"1";
"B"
$PN"2"34;
"A"
$PN"1"63;
%"Q_CAP"
"1","(-2900,-1225)","0","pure_quanta","I253";
;
PART_NUMBER"CH5104KEB02"
VOLTAGE"25V"
VALUE"1UF"
MATERIAL"X6S"
TOLERANCE"10%"
PACK_TYPE"C0402"
CDS_LIB"pure_quanta"
LOCATION"C277"
$SEC"1"
CDS_SEC"1";
"B"
$PN"2"33;
"A"
$PN"1"67;
%"UNIVERSAL_GND"
"1","(-2725,-1525)","0","logical_power","I254";
;
CDS_LIB"logical_power"
HDL_POWER"GND";
"A"33;
%"Q_CAP"
"1","(-2550,-1225)","0","pure_quanta","I255";
;
VOLTAGE"25V"
PART_NUMBER"CH4104K1B00"
MATERIAL"X7R"
TOLERANCE"10%"
VALUE"0.1UF"
PACK_TYPE"0402"
CDS_LIB"pure_quanta"
LOCATION"C279"
$SEC"1"
CDS_SEC"1";
"B"
$PN"2"33;
"A"
$PN"1"67;
%"Q_RES"
"1","(-1125,-1050)","0","pure_quanta","I256";
;
VALUE"0"
TOLERANCE"5%"
MATERIAL"EMPTY"
WATTAGE"1/16W"
PACK_TYPE"0402LF"
PART_NUMBER"CS00002JB13"
CDS_LIB"pure_quanta"
LOCATION"R780"
$SEC"1"
CDS_SEC"1";
"B"
$PN"2"63;
"A"
$PN"1"16;
%"Q_RES"
"1","(-3425,-1050)","0","pure_quanta","I259";
;
VALUE"0"
TOLERANCE"5%"
WATTAGE"1/16W"
MATERIAL"CHIP"
PACK_TYPE"0402LF"
PART_NUMBER"CS00002JB13"
CDS_LIB"pure_quanta"
LOCATION"R779"
$SEC"1"
CDS_SEC"1";
"B"
$PN"2"67;
"A"
$PN"1"5;
%"Q_RES"
"1","(-1225,-1325)","0","pure_quanta","I260";
;
VALUE"0"
TOLERANCE"5%"
WATTAGE"1/16W"
MATERIAL"CHIP"
PACK_TYPE"0402LF"
PART_NUMBER"CS00002JB13"
CDS_LIB"pure_quanta"
LOCATION"R783"
$SEC"1"
CDS_SEC"1";
"B"
$PN"2"63;
"A"
$PN"1"17;
%"UNIVERSAL_POWER"
"1","(-1650,-1175)","0","logical_power","I261";
;
HDL_POWER"P1V8_AUX"
CDS_LIB"logical_power";
"A"17;
%"UNIVERSAL_POWER"
"1","(-3950,-1175)","0","logical_power","I262";
;
HDL_POWER"P1V8_AUX"
CDS_LIB"logical_power";
"A"4;
%"Q_RES"
"1","(-3525,-1325)","0","pure_quanta","I263";
;
VALUE"0"
TOLERANCE"5%"
MATERIAL"EMPTY"
WATTAGE"1/16W"
PACK_TYPE"0402LF"
PART_NUMBER"CS00002JB13"
CDS_LIB"pure_quanta"
LOCATION"R781"
$SEC"1"
CDS_SEC"1";
"B"
$PN"2"67;
"A"
$PN"1"4;
%"Q_RES"
"1","(-3525,-1600)","0","pure_quanta","I264";
;
VALUE"0"
TOLERANCE"5%"
MATERIAL"EMPTY"
PACK_TYPE"0402LF"
PART_NUMBER"CS00002JB13"
WATTAGE"1/16W"
CDS_LIB"pure_quanta"
LOCATION"R782"
$SEC"1"
CDS_SEC"1";
"B"
$PN"2"67;
"A"
$PN"1"14;
%"Q_RES"
"1","(-1225,-1600)","0","pure_quanta","I267";
;
PACK_TYPE"0402LF"
WATTAGE"1/16W"
TOLERANCE"5%"
VALUE"0"
MATERIAL"EMPTY"
PART_NUMBER"CS00002JB13"
CDS_LIB"pure_quanta"
LOCATION"R784"
$SEC"1"
CDS_SEC"1";
"B"
$PN"2"63;
"A"
$PN"1"15;
%"VCCAUX15"
"1","(-1550,-900)","0","logical_power","I268";
;
HDL_POWER"P2V5_AUX"
CDS_LIB"logical_power";
"A"16;
%"VCCAUX15"
"1","(-3850,-900)","0","logical_power","I269";
;
HDL_POWER"P2V5_AUX"
CDS_LIB"logical_power";
"A"5;
%"VCCAUX15"
"1","(-1650,-1450)","0","logical_power","I270";
;
HDL_POWER"P1V2_AUX"
CDS_LIB"logical_power";
"A"15;
%"VCCAUX15"
"1","(-3950,-1450)","0","logical_power","I271";
;
HDL_POWER"P1V2_AUX"
CDS_LIB"logical_power";
"A"14;
%"Q_INDUCTOR"
"1","(-125,650)","6","pure_quanta","I272";
;
PART_NUMBER"CX8PG121009"
VALUE"BLM18PG121SN1D/2000MA"
MATERIAL"IND"
PACK_TYPE"SMLF"
NEEDS_NO_SIZE"TRUE"
CDS_LIB"pure_quanta"
LOCATION"L2"
$SEC"1"
CDS_SEC"1";
"1"
$PN"1"3;
"2"
$PN"2"61;
%"VCCAUX15"
"1","(-450,750)","0","logical_power","I273";
;
HDL_POWER"P1V2_AUX"
CDS_LIB"logical_power";
"A"3;
%"MOSFET_NCH_4D1S"
"1","(3725,850)","6","pure_quanta","I274";
;
VALUE"NTGS4141NT1G"
MATERIAL"IC"
PART_NUMBER"BAM41410005"
PART_TYPE"SMLF"
CDS_LMAN_SYM_OUTLINE"-125,125,125,-125"
PIN_NAMES_ROTATE"True"
CDS_LIB"pure_quanta"
SEC_TYPE""
LOCATION"Q5"
SEC"1";
"5"
$PN"5"55;
"4"
$PN"4"9;
"2"
$PN"2"55;
"3"
$PN"3"52;
"6"
$PN"6"55;
"1"
$PN"1"55;
%"UNIVERSAL_POWER"
"1","(3750,1325)","0","logical_power","I276";
;
HDL_POWER"P1V8_AUX"
CDS_LIB"logical_power";
"A"9;
%"Q_RES"
"2","(4350,800)","0","pure_quanta","I278";
;
PACK_TYPE"0603LF"
TOLERANCE"5%"
MATERIAL"EMPTY"
VALUE"0"
PART_NUMBER"CS00003J910"
WATTAGE"1/10W"
CDS_LIB"pure_quanta"
LOCATION"R645"
$SEC"1"
CDS_SEC"1";
"A"
$PN"1"9;
"B"
$PN"2"55;
%"Q_RES"
"2","(4350,0)","0","pure_quanta","I279";
;
VALUE"0"
WATTAGE"1/10W"
PACK_TYPE"0603LF"
PART_NUMBER"CS00003J910"
MATERIAL"EMPTY"
TOLERANCE"5%"
CDS_LIB"pure_quanta"
LOCATION"R646"
$SEC"1"
CDS_SEC"1";
"A"
$PN"1"55;
"B"
$PN"2"2;
%"UNIVERSAL_POWER"
"1","(4925,225)","0","logical_power","I283";
;
HDL_POWER"P3V3_AUX"
CDS_LIB"logical_power";
"A"2;
%"Q_RES"
"2","(1725,-400)","0","pure_quanta","I284";
;
VALUE"150K"
TOLERANCE"1%"
WATTAGE"1/16W"
PACK_TYPE"0402LF"
PART_NUMBER"CS41502FB04"
MATERIAL"EMPTY"
CDS_LIB"pure_quanta"
LOCATION"R493"
$SEC"1"
CDS_SEC"1";
"A"
$PN"1"52;
"B"
$PN"2"29;
%"UNIVERSAL_GND"
"1","(1725,-700)","0","logical_power","I285";
;
CDS_LIB"logical_power"
HDL_POWER"GND";
"A"29;
%"AST2600A3GP"
"6","(-3075,1675)","0","pure_quanta","I286";
;
MATERIAL"IC"
PART_NUMBER"AJ026000T06"
PART_TYPE"SMLF"
VALUE"AST2600A3-GP"
CDS_LIB"pure_quanta"
CDS_LMAN_SYM_OUTLINE"-375,2050,375,-2050"
NEEDS_NO_SIZE"TRUE"
LOCATION"U5"
$SEC"6"
CDS_SEC"6";
"GND_U23"
$PN"U23"38;
"GND_AA20"
$PN"AA20"38;
"GND_P19"
$PN"P19"50;
"GND_P18"
$PN"P18"50;
"GND_P17"
$PN"P17"50;
"GND_P16"
$PN"P16"50;
"GND_P15"
$PN"P15"50;
"GND_P10"
$PN"P10"50;
"GND_P9"
$PN"P9"50;
"GND_P4"
$PN"P4"50;
"GND_AF26"
$PN"AF26"38;
"GND_AF4"
$PN"AF4"38;
"GND_AF1"
$PN"AF1"38;
"GND_AE23"
$PN"AE23"38;
"GND_AE20"
$PN"AE20"38;
"GND_AE17"
$PN"AE17"38;
"GND_AE13"
$PN"AE13"38;
"GND_AE9"
$PN"AE9"38;
"GND_AE6"
$PN"AE6"38;
"GND_AE3"
$PN"AE3"38;
"GND_AD4"
$PN"AD4"38;
"GND_AD1"
$PN"AD1"38;
"GND_AC25"
$PN"AC25"38;
"GND_AC6"
$PN"AC6"38;
"GND_AC2"
$PN"AC2"38;
"GND_AA22"
$PN"AA22"38;
"GND_AA19"
$PN"AA19"38;
"GND_AA15"
$PN"AA15"38;
"GND_AA14"
$PN"AA14"38;
"GND_AA10"
$PN"AA10"38;
"GND_N19"
$PN"N19"50;
"GND_N18"
$PN"N18"50;
"GND_N17"
$PN"N17"50;
"GND_N16"
$PN"N16"50;
"GND_N15"
$PN"N15"50;
"GND_N10"
$PN"N10"50;
"GND_N9"
$PN"N9"50;
"GND_N6"
$PN"N6"50;
"GND_N2"
$PN"N2"50;
"GND_M19"
$PN"M19"50;
"GND_M18"
$PN"M18"50;
"GND_AA6"
$PN"AA6"38;
"GND_AA7"
$PN"AA7"38;
"GND_AA8"
$PN"AA8"38;
"GND_AA3"
$PN"AA3"38;
"GND_AA1"
$PN"AA1"38;
"GND_Y22"
$PN"Y22"38;
"GND_Y6"
$PN"Y6"38;
"GND_W25"
$PN"W25"38;
"GND_W22"
$PN"W22"38;
"GND_M17"
$PN"M17"50;
"GND_M16"
$PN"M16"50;
"GND_M15"
$PN"M15"50;
"GND_M12"
$PN"M12"50;
"GND_M10"
$PN"M10"50;
"GND_M9"
$PN"M9"50;
"GND_M4"
$PN"M4"50;
"GND_L25"
$PN"L25"50;
"GND_L19"
$PN"L19"50;
"GND_L18"
$PN"L18"50;
"GND_W12"
$PN"W12"38;
"GND_W11"
$PN"W11"38;
"GND_W10"
$PN"W10"38;
"GND_W9"
$PN"W9"38;
"GND_W8"
$PN"W8"38;
"GND_W6"
$PN"W6"38;
"GND_W5"
$PN"W5"38;
"GND_V19"
$PN"V19"38;
"GND_V18"
$PN"V18"38;
"GND_V17"
$PN"V17"38;
"GND_V16"
$PN"V16"38;
"GND_V15"
$PN"V15"38;
"GND_V14"
$PN"V14"38;
"GND_V12"
$PN"V12"38;
"GND_V11"
$PN"V11"38;
"GND_V5"
$PN"V5"38;
"GND_U22"
$PN"U22"38;
"GND_U19"
$PN"U19"38;
"GND_U14"
$PN"U14"38;
"GND_U12"
$PN"U12"38;
"GND_U11"
$PN"U11"38;
"GND_U10"
$PN"U10"38;
"GND_U9"
$PN"U9"38;
"GND_U8"
$PN"U8"38;
"GND_U2"
$PN"U2"38;
"GND_T19"
$PN"T19"38;
"GND_T18"
$PN"T18"38;
"GND_T17"
$PN"T17"38;
"GND_T16"
$PN"T16"38;
"GND_T15"
$PN"T15"38;
"GND_T12"
$PN"T12"38;
"GND_T11"
$PN"T11"38;
"GND_T4"
$PN"T4"38;
"GND_R25"
$PN"R25"38;
"GND_R19"
$PN"R19"38;
"GND_R18"
$PN"R18"38;
"GND_R17"
$PN"R17"38;
"GND_R16"
$PN"R16"38;
"GND_R15"
$PN"R15"38;
"GND_R11"
$PN"R11"38;
"GND_R8"
$PN"R8"38;
"GND_R2"
$PN"R2"38;
"GND_L17"
$PN"L17"50;
"GND_L16"
$PN"L16"50;
"GND_L15"
$PN"L15"50;
"GND_L12"
$PN"L12"50;
"GND_L11"
$PN"L11"50;
"GND_L8"
$PN"L8"50;
"GND_L2"
$PN"L2"50;
"GND_K22"
$PN"K22"50;
"GND_K15"
$PN"K15"50;
"GND_K14"
$PN"K14"50;
"GND_K13"
$PN"K13"50;
"GND_K9"
$PN"K9"50;
"GND_K8"
$PN"K8"50;
"GND_K4"
$PN"K4"50;
"GND_J19"
$PN"J19"50;
"GND_J18"
$PN"J18"50;
"GND_J17"
$PN"J17"50;
"GND_J16"
$PN"J16"50;
"GND_J15"
$PN"J15"50;
"GND_J14"
$PN"J14"50;
"GND_J13"
$PN"J13"50;
"GND_J11"
$PN"J11"50;
"GND_J2"
$PN"J2"50;
"GND_H13"
$PN"H13"50;
"GND_H11"
$PN"H11"50;
"GND_H10"
$PN"H10"50;
"GND_H9"
$PN"H9"50;
"GND_H4"
$PN"H4"50;
"GND_G25"
$PN"G25"50;
"GND_G2"
$PN"G2"50;
"GND_F21"
$PN"F21"50;
"GND_F18"
$PN"F18"50;
"GND_F17"
$PN"F17"50;
"GND_F16"
$PN"F16"50;
"GND_F14"
$PN"F14"50;
"GND_F12"
$PN"F12"50;
"GND_F10"
$PN"F10"50;
"GND_F8"
$PN"F8"50;
"GND_F6"
$PN"F6"50;
"GND_E8"
$PN"E8"50;
"GND_D25"
$PN"D25"50;
"GND_C3"
$PN"C3"50;
"GND_B23"
$PN"B23"50;
"GND_B19"
$PN"B19"50;
"GND_B15"
$PN"B15"50;
"GND_B11"
$PN"B11"50;
"GND_B5"
$PN"B5"50;
"GND_A26"
$PN"A26"50;
"GND_A5"
$PN"A5"50;
"GND_A1"
$PN"A1"50;
%"MOSFET_PCH_GDS"
"1","(3475,-125)","6","pure_quanta","I289";
;
VALUE"NTR1P02LT1G"
PART_TYPE"SMLF"
PART_NUMBER"BAM1P020000"
MATERIAL"EMPTY"
CDS_LIB"pure_quanta"
PIN_NAMES_ROTATE"True"
CDS_LMAN_SYM_OUTLINE"-125,100,125,-100"
LOCATION"Q4"
$SEC"1"
CDS_SEC"1";
"S"
$PN"S"2;
"G"
$PN"G"52;
"D"
$PN"D"55;
%"UNIVERSAL_POWER"
"1","(2775,3025)","0","logical_power","I90";
;
HDL_POWER"P1V0_AUX"
CDS_LIB"logical_power";
"A"13;
%"UNIVERSAL_POWER"
"1","(2775,3775)","0","logical_power","I91";
;
HDL_POWER"P1V0_AUX"
CDS_LIB"logical_power";
"A"12;
%"Q_RES"
"1","(3350,2875)","0","pure_quanta","I92";
;
PART_NUMBER"CS00002JB13"
VALUE"0"
TOLERANCE"5%"
WATTAGE"1/16W"
MATERIAL"CHIP"
PACK_TYPE"0402LF"
CDS_LIB"pure_quanta"
LOCATION"R281"
$SEC"1"
CDS_SEC"1";
"B"
$PN"2"24;
"A"
$PN"1"13;
%"UNIVERSAL_POWER"
"1","(2975,3425)","0","logical_power","I93";
;
HDL_POWER"P1V2_AUX"
CDS_LIB"logical_power";
"A"11;
%"Q_RES"
"1","(3350,3175)","0","pure_quanta","I94";
;
TOLERANCE"5%"
VALUE"0"
MATERIAL"EMPTY"
WATTAGE"1/16W"
PACK_TYPE"0402LF"
PART_NUMBER"CS00002JB13"
CDS_LIB"pure_quanta"
LOCATION"R280"
$SEC"1"
CDS_SEC"1";
"B"
$PN"2"24;
"A"
$PN"1"11;
%"Q_RES"
"1","(3350,3625)","0","pure_quanta","I95";
;
VALUE"0"
TOLERANCE"5%"
WATTAGE"1/16W"
MATERIAL"CHIP"
PACK_TYPE"0402LF"
PART_NUMBER"CS00002JB13"
CDS_LIB"pure_quanta"
LOCATION"R279"
$SEC"1"
CDS_SEC"1";
"B"
$PN"2"22;
"A"
$PN"1"12;
%"UNIVERSAL_GND"
"1","(4100,2825)","0","logical_power","I96";
;
CDS_LIB"logical_power"
HDL_POWER"GND";
"A"32;
%"Q_CAP"
"1","(4100,3025)","0","pure_quanta","I97";
;
VALUE"0.1UF"
VOLTAGE"25V"
PART_NUMBER"CH4104K1B00"
MATERIAL"X7R"
TOLERANCE"10%"
PACK_TYPE"0402"
CDS_LIB"pure_quanta"
LOCATION"C140"
$SEC"1"
CDS_SEC"1";
"B"
$PN"2"32;
"A"
$PN"1"24;
%"Q_CAP"
"1","(4100,3775)","0","pure_quanta","I98";
;
VOLTAGE"25V"
PART_NUMBER"CH4104K1B00"
MATERIAL"X7R"
TOLERANCE"10%"
VALUE"0.1UF"
PACK_TYPE"0402"
CDS_LIB"pure_quanta"
LOCATION"C139"
$SEC"1"
CDS_SEC"1";
"B"
$PN"2"31;
"A"
$PN"1"22;
%"UNIVERSAL_GND"
"1","(4100,3575)","0","logical_power","I99";
;
CDS_LIB"logical_power"
HDL_POWER"GND";
"A"31;
END.
